(kicad_pcb
	(version 20260206)
	(generator "pcbnew")
	(generator_version "10.0")
	(general
		(thickness 1.6)
		(legacy_teardrops no)
	)
	(paper "A4")
	(title_block
		(title "01162023_DA0F0TEBIF0_F0T_Expander_BD_F_brd_V02_OCP.brd")
		(comment 1 "Grand Teton / footprints 5852-5858 of 9728")
	)
	(layers
		(0 "F.Cu" signal "TOP")
		(4 "In1.Cu" signal "GND")
		(6 "In2.Cu" signal "VCC")
		(8 "In3.Cu" signal "VCC1")
		(10 "In4.Cu" signal "GND1")
		(12 "In5.Cu" signal "IN1")
		(14 "In6.Cu" signal "GND2")
		(16 "In7.Cu" signal "IN2")
		(18 "In8.Cu" signal "GND3")
		(20 "In9.Cu" signal "IN3")
		(22 "In10.Cu" signal "GND4")
		(24 "In11.Cu" signal "IN4")
		(26 "In12.Cu" signal "GND5")
		(28 "In13.Cu" signal "IN5")
		(30 "In14.Cu" signal "GND6")
		(32 "In15.Cu" signal "IN6")
		(34 "In16.Cu" signal "GND7")
		(2 "B.Cu" signal "BOTTOM")
		(9 "F.Adhes" user "F.Adhesive")
		(11 "B.Adhes" user "B.Adhesive")
		(13 "F.Paste" user "Package Geometry/Pastemask Top")
		(15 "B.Paste" user "Package Geometry/Pastemask Bottom")
		(5 "F.SilkS" user "Ref Des/Silkscreen Top")
		(7 "B.SilkS" user "Ref Des/Silkscreen Bottom")
		(1 "F.Mask" user "Board Geometry/Soldermask Top")
		(3 "B.Mask" user "Board Geometry/Soldermask Bottom")
		(17 "Dwgs.User" user "User.Drawings")
		(19 "Cmts.User" user "User.Comments")
		(21 "Eco1.User" user "User.Eco1")
		(23 "Eco2.User" user "User.Eco2")
		(25 "Edge.Cuts" user "Board Geometry/Outline")
		(27 "Margin" user)
		(31 "F.CrtYd" user "Package Geometry/Place Bound Top")
		(29 "B.CrtYd" user "Package Geometry/Place Bound Bottom")
		(35 "F.Fab" user "Ref Des/Assembly Top")
		(33 "B.Fab" user "Ref Des/Assembly Bottom")
	)
	(footprint ""
		(layer "F.Cu")
		(at 238.123476 -44.451524)
		(property "Reference" "PD68"
			(at 1.500124 2.136394 0)
			(unlocked yes)
			(layer "F.SilkS")
			(effects
				(font
					(size 0.7874 0.5842)
					(thickness 0.1524)
				)
				(justify left)
			)
		)
		(property "Value" ""
			(at 0 0 0)
			(layer "F.Fab")
			(effects
				(font
					(size 1.27 1.27)
				)
			)
		)
		(duplicate_pad_numbers_are_jumpers no)
		(fp_line
			(start -3.400044 -1.459992)
			(end 4.107942 -1.459992)
			(stroke
				(width 0.1524)
				(type default)
			)
			(layer "F.SilkS")
		)
		(fp_line
			(start -3.400044 1.459992)
			(end -3.400044 -1.459992)
			(stroke
				(width 0.1524)
				(type default)
			)
			(layer "F.SilkS")
		)
		(fp_line
			(start 4.107942 -1.459992)
			(end 4.107942 1.459992)
			(stroke
				(width 0.1524)
				(type default)
			)
			(layer "F.SilkS")
		)
		(fp_line
			(start 4.107942 1.459992)
			(end -3.400044 1.459992)
			(stroke
				(width 0.1524)
				(type default)
			)
			(layer "F.SilkS")
		)
		(fp_poly
			(pts
				(xy 4.107942 -1.459992) (xy 4.107942 1.459992) (xy 3.308096 1.459992) (xy 3.308096 -1.459992)
			)
			(stroke
				(width 0)
				(type default)
			)
			(fill yes)
			(layer "F.SilkS")
		)
		(fp_line
			(start -2.29997 -1.459992)
			(end 2.29997 -1.459992)
			(stroke
				(width 0.1)
				(type default)
			)
			(layer "F.Fab")
		)
		(fp_line
			(start -2.29997 1.459992)
			(end -2.29997 -1.459992)
			(stroke
				(width 0.1)
				(type default)
			)
			(layer "F.Fab")
		)
		(fp_line
			(start 2.29997 -1.459992)
			(end 2.29997 1.459992)
			(stroke
				(width 0.1)
				(type default)
			)
			(layer "F.Fab")
		)
		(fp_line
			(start 2.29997 1.459992)
			(end -2.29997 1.459992)
			(stroke
				(width 0.1)
				(type default)
			)
			(layer "F.Fab")
		)
		(fp_text user "+"
			(at -4.7752 -0.12065 0)
			(unlocked yes)
			(layer "F.SilkS")
			(effects
				(font
					(size 1.905 1.4224)
					(thickness 0.1524)
				)
				(justify left)
			)
		)
		(fp_text user "-"
			(at 5.4102 0.29845 180)
			(unlocked yes)
			(layer "F.SilkS")
			(effects
				(font
					(size 1.905 1.4224)
					(thickness 0.1524)
				)
				(justify left)
			)
		)
		(fp_text user "+"
			(at -4.7752 -0.12065 0)
			(unlocked yes)
			(layer "F.Fab")
			(effects
				(font
					(size 1.905 1.4224)
					(thickness 0.1524)
				)
				(justify left)
			)
		)
		(fp_text user "-"
			(at 5.4102 0.29845 180)
			(unlocked yes)
			(layer "F.Fab")
			(effects
				(font
					(size 1.905 1.4224)
					(thickness 0.1524)
				)
				(justify left)
			)
		)
		(pad "A" smd rect
			(at -1.999996 0 90)
			(size 1.7018 2.5146)
			(layers "F.Cu" "F.Mask" "F.Paste")
			(net "GND")
		)
		(pad "C" smd rect
			(at 1.999996 0 90)
			(size 1.7018 2.5146)
			(layers "F.Cu" "F.Mask" "F.Paste")
			(net "P3V3_SSD8")
		)
	)
	(footprint ""
		(layer "F.Cu")
		(at 297.55719 -213.523068 -90)
		(property "Reference" "R3395"
			(at 0 0 270)
			(layer "F.SilkS")
			(hide yes)
			(effects
				(font
					(size 1.27 1.27)
				)
			)
		)
		(property "Value" ""
			(at 0 0 270)
			(layer "F.Fab")
			(effects
				(font
					(size 1.27 1.27)
				)
			)
		)
		(duplicate_pad_numbers_are_jumpers no)
		(fp_line
			(start -0.7874 0.4064)
			(end -0.7874 -0.4064)
			(stroke
				(width 0.1524)
				(type default)
			)
			(layer "F.SilkS")
		)
		(fp_line
			(start 0.7874 0.4064)
			(end -0.7874 0.4064)
			(stroke
				(width 0.1524)
				(type default)
			)
			(layer "F.SilkS")
		)
		(fp_line
			(start -0.7874 -0.4064)
			(end 0.7874 -0.4064)
			(stroke
				(width 0.1524)
				(type default)
			)
			(layer "F.SilkS")
		)
		(fp_line
			(start 0.7874 -0.4064)
			(end 0.7874 0.4064)
			(stroke
				(width 0.1524)
				(type default)
			)
			(layer "F.SilkS")
		)
		(fp_line
			(start -0.67945 0.3048)
			(end -0.67945 -0.305054)
			(stroke
				(width 0.1)
				(type default)
			)
			(layer "F.Fab")
		)
		(fp_line
			(start -0.12065 0.3048)
			(end -0.67945 0.3048)
			(stroke
				(width 0.1)
				(type default)
			)
			(layer "F.Fab")
		)
		(fp_line
			(start 0.120396 0.3048)
			(end 0.120396 0.2794)
			(stroke
				(width 0.1)
				(type default)
			)
			(layer "F.Fab")
		)
		(fp_line
			(start 0.67945 0.3048)
			(end 0.120396 0.3048)
			(stroke
				(width 0.1)
				(type default)
			)
			(layer "F.Fab")
		)
		(fp_line
			(start -0.12065 0.2794)
			(end -0.12065 0.3048)
			(stroke
				(width 0.1)
				(type default)
			)
			(layer "F.Fab")
		)
		(fp_line
			(start 0.120396 0.2794)
			(end -0.12065 0.2794)
			(stroke
				(width 0.1)
				(type default)
			)
			(layer "F.Fab")
		)
		(fp_line
			(start -0.12065 -0.2794)
			(end 0.12065 -0.2794)
			(stroke
				(width 0.1)
				(type default)
			)
			(layer "F.Fab")
		)
		(fp_line
			(start 0.12065 -0.2794)
			(end 0.12065 -0.3048)
			(stroke
				(width 0.1)
				(type default)
			)
			(layer "F.Fab")
		)
		(fp_line
			(start 0.12065 -0.3048)
			(end 0.67945 -0.3048)
			(stroke
				(width 0.1)
				(type default)
			)
			(layer "F.Fab")
		)
		(fp_line
			(start 0.67945 -0.3048)
			(end 0.67945 0.3048)
			(stroke
				(width 0.1)
				(type default)
			)
			(layer "F.Fab")
		)
		(fp_line
			(start -0.67945 -0.305054)
			(end -0.12065 -0.305054)
			(stroke
				(width 0.1)
				(type default)
			)
			(layer "F.Fab")
		)
		(fp_line
			(start -0.12065 -0.305054)
			(end -0.12065 -0.2794)
			(stroke
				(width 0.1)
				(type default)
			)
			(layer "F.Fab")
		)
		(pad "1" smd circle
			(at -0.40005 0 270)
			(size 0 0)
			(layers "F.Cu" "F.Mask" "F.Paste")
			(net "SPI_BIC1_CLK_LS23_R1")
		)
		(pad "2" smd circle
			(at 0.40005 0 270)
			(size 0 0)
			(layers "F.Cu" "F.Mask" "F.Paste")
			(net "SPI_BIC1_CLK_LS23_R")
		)
	)
	(footprint ""
		(layer "F.Cu")
		(at 19.307048 -350.098614 90)
		(property "Reference" "C191"
			(at 0 0 90)
			(layer "F.SilkS")
			(hide yes)
			(effects
				(font
					(size 1.27 1.27)
				)
			)
		)
		(property "Value" ""
			(at 0 0 90)
			(layer "F.Fab")
			(effects
				(font
					(size 1.27 1.27)
				)
			)
		)
		(duplicate_pad_numbers_are_jumpers no)
		(fp_line
			(start 0.299974 -0.150114)
			(end 0.299974 0.150114)
			(stroke
				(width 0.1)
				(type default)
			)
			(layer "F.Fab")
		)
		(fp_line
			(start -0.299974 -0.150114)
			(end 0.299974 -0.150114)
			(stroke
				(width 0.1)
				(type default)
			)
			(layer "F.Fab")
		)
		(fp_line
			(start 0.299974 0.150114)
			(end -0.299974 0.150114)
			(stroke
				(width 0.1)
				(type default)
			)
			(layer "F.Fab")
		)
		(fp_line
			(start -0.299974 0.150114)
			(end -0.299974 -0.150114)
			(stroke
				(width 0.1)
				(type default)
			)
			(layer "F.Fab")
		)
		(pad "1" smd rect
			(at -0.2667 0 90)
			(size 0.3048 0.381)
			(layers "F.Cu" "F.Mask" "F.Paste")
			(net "P5E_PEX0_STN7_TX_DP<112>")
		)
		(pad "2" smd rect
			(at 0.2667 0 90)
			(size 0.3048 0.381)
			(layers "F.Cu" "F.Mask" "F.Paste")
			(net "P5E_PEX0_STN7_TX_C_DP<112>")
		)
	)
	(footprint ""
		(layer "F.Cu")
		(at 320.851276 -227.295964 180)
		(property "Reference" "R2987"
			(at 0 0 180)
			(layer "F.SilkS")
			(hide yes)
			(effects
				(font
					(size 1.27 1.27)
				)
			)
		)
		(property "Value" ""
			(at 0 0 180)
			(layer "F.Fab")
			(effects
				(font
					(size 1.27 1.27)
				)
			)
		)
		(duplicate_pad_numbers_are_jumpers no)
		(fp_line
			(start 0.7874 0.4064)
			(end -0.7874 0.4064)
			(stroke
				(width 0.1524)
				(type default)
			)
			(layer "F.SilkS")
		)
		(fp_line
			(start 0.7874 -0.4064)
			(end 0.7874 0.4064)
			(stroke
				(width 0.1524)
				(type default)
			)
			(layer "F.SilkS")
		)
		(fp_line
			(start -0.7874 0.4064)
			(end -0.7874 -0.4064)
			(stroke
				(width 0.1524)
				(type default)
			)
			(layer "F.SilkS")
		)
		(fp_line
			(start -0.7874 -0.4064)
			(end 0.7874 -0.4064)
			(stroke
				(width 0.1524)
				(type default)
			)
			(layer "F.SilkS")
		)
		(fp_line
			(start 0.67945 0.3048)
			(end 0.120396 0.3048)
			(stroke
				(width 0.1)
				(type default)
			)
			(layer "F.Fab")
		)
		(fp_line
			(start 0.67945 -0.3048)
			(end 0.67945 0.3048)
			(stroke
				(width 0.1)
				(type default)
			)
			(layer "F.Fab")
		)
		(fp_line
			(start 0.12065 -0.2794)
			(end 0.12065 -0.3048)
			(stroke
				(width 0.1)
				(type default)
			)
			(layer "F.Fab")
		)
		(fp_line
			(start 0.12065 -0.3048)
			(end 0.67945 -0.3048)
			(stroke
				(width 0.1)
				(type default)
			)
			(layer "F.Fab")
		)
		(fp_line
			(start 0.120396 0.3048)
			(end 0.120396 0.2794)
			(stroke
				(width 0.1)
				(type default)
			)
			(layer "F.Fab")
		)
		(fp_line
			(start 0.120396 0.2794)
			(end -0.12065 0.2794)
			(stroke
				(width 0.1)
				(type default)
			)
			(layer "F.Fab")
		)
		(fp_line
			(start -0.12065 0.3048)
			(end -0.67945 0.3048)
			(stroke
				(width 0.1)
				(type default)
			)
			(layer "F.Fab")
		)
		(fp_line
			(start -0.12065 0.2794)
			(end -0.12065 0.3048)
			(stroke
				(width 0.1)
				(type default)
			)
			(layer "F.Fab")
		)
		(fp_line
			(start -0.12065 -0.2794)
			(end 0.12065 -0.2794)
			(stroke
				(width 0.1)
				(type default)
			)
			(layer "F.Fab")
		)
		(fp_line
			(start -0.12065 -0.305054)
			(end -0.12065 -0.2794)
			(stroke
				(width 0.1)
				(type default)
			)
			(layer "F.Fab")
		)
		(fp_line
			(start -0.67945 0.3048)
			(end -0.67945 -0.305054)
			(stroke
				(width 0.1)
				(type default)
			)
			(layer "F.Fab")
		)
		(fp_line
			(start -0.67945 -0.305054)
			(end -0.12065 -0.305054)
			(stroke
				(width 0.1)
				(type default)
			)
			(layer "F.Fab")
		)
		(pad "1" smd circle
			(at -0.40005 0 180)
			(size 0 0)
			(layers "F.Cu" "F.Mask" "F.Paste")
			(net "P3V3_AUX")
		)
		(pad "2" smd circle
			(at 0.40005 0 180)
			(size 0 0)
			(layers "F.Cu" "F.Mask" "F.Paste")
			(net "FPGA_DEBUG_LED_R_N")
		)
	)
	(footprint ""
		(layer "F.Cu")
		(at 375.230136 -284.404308 -90)
		(property "Reference" "C3573"
			(at 0 0 270)
			(layer "F.SilkS")
			(hide yes)
			(effects
				(font
					(size 1.27 1.27)
				)
			)
		)
		(property "Value" ""
			(at 0 0 270)
			(layer "F.Fab")
			(effects
				(font
					(size 1.27 1.27)
				)
			)
		)
		(duplicate_pad_numbers_are_jumpers no)
		(fp_line
			(start -1.2954 0.5842)
			(end -1.2954 -0.5842)
			(stroke
				(width 0.1524)
				(type default)
			)
			(layer "F.SilkS")
		)
		(fp_line
			(start 1.2954 0.5842)
			(end -1.2954 0.5842)
			(stroke
				(width 0.1524)
				(type default)
			)
			(layer "F.SilkS")
		)
		(fp_line
			(start -1.2954 -0.5842)
			(end 1.2954 -0.5842)
			(stroke
				(width 0.1524)
				(type default)
			)
			(layer "F.SilkS")
		)
		(fp_line
			(start 1.2954 -0.5842)
			(end 1.2954 0.5842)
			(stroke
				(width 0.1524)
				(type default)
			)
			(layer "F.SilkS")
		)
		(fp_line
			(start -0.8636 0.4572)
			(end -0.8636 0.4064)
			(stroke
				(width 0.1)
				(type default)
			)
			(layer "F.Fab")
		)
		(fp_line
			(start 0.8636 0.4572)
			(end -0.8636 0.4572)
			(stroke
				(width 0.1)
				(type default)
			)
			(layer "F.Fab")
		)
		(fp_line
			(start -1.1938 0.4064)
			(end -1.1938 -0.4064)
			(stroke
				(width 0.1)
				(type default)
			)
			(layer "F.Fab")
		)
		(fp_line
			(start -0.8636 0.4064)
			(end -1.1938 0.4064)
			(stroke
				(width 0.1)
				(type default)
			)
			(layer "F.Fab")
		)
		(fp_line
			(start 0.8636 0.4064)
			(end 0.8636 0.4572)
			(stroke
				(width 0.1)
				(type default)
			)
			(layer "F.Fab")
		)
		(fp_line
			(start 1.1938 0.4064)
			(end 0.8636 0.4064)
			(stroke
				(width 0.1)
				(type default)
			)
			(layer "F.Fab")
		)
		(fp_line
			(start -1.1938 -0.4064)
			(end -0.8636 -0.4064)
			(stroke
				(width 0.1)
				(type default)
			)
			(layer "F.Fab")
		)
		(fp_line
			(start -0.8636 -0.4064)
			(end -0.8636 -0.4572)
			(stroke
				(width 0.1)
				(type default)
			)
			(layer "F.Fab")
		)
		(fp_line
			(start 0.8636 -0.4064)
			(end 1.1938 -0.4064)
			(stroke
				(width 0.1)
				(type default)
			)
			(layer "F.Fab")
		)
		(fp_line
			(start 1.1938 -0.4064)
			(end 1.1938 0.4064)
			(stroke
				(width 0.1)
				(type default)
			)
			(layer "F.Fab")
		)
		(fp_line
			(start -0.8636 -0.4572)
			(end 0.8636 -0.4572)
			(stroke
				(width 0.1)
				(type default)
			)
			(layer "F.Fab")
		)
		(fp_line
			(start 0.8636 -0.4572)
			(end 0.8636 -0.4064)
			(stroke
				(width 0.1)
				(type default)
			)
			(layer "F.Fab")
		)
		(pad "1" smd rect
			(at -0.7366 0 180)
			(size 0.7112 0.8128)
			(layers "F.Cu" "F.Mask" "F.Paste")
			(net "P1V8_PLL0_PEX3")
		)
		(pad "2" smd rect
			(at 0.7366 0 180)
			(size 0.7112 0.8128)
			(layers "F.Cu" "F.Mask" "F.Paste")
			(net "GND")
		)
	)
	(footprint ""
		(layer "F.Cu")
		(at 341.63 -201.168 90)
		(property "Reference" "R4143"
			(at 0 0 90)
			(layer "F.SilkS")
			(hide yes)
			(effects
				(font
					(size 1.27 1.27)
				)
			)
		)
		(property "Value" ""
			(at 0 0 90)
			(layer "F.Fab")
			(effects
				(font
					(size 1.27 1.27)
				)
			)
		)
		(duplicate_pad_numbers_are_jumpers no)
		(fp_line
			(start 0.7874 -0.4064)
			(end 0.7874 0.4064)
			(stroke
				(width 0.1524)
				(type default)
			)
			(layer "F.SilkS")
		)
		(fp_line
			(start -0.7874 -0.4064)
			(end 0.7874 -0.4064)
			(stroke
				(width 0.1524)
				(type default)
			)
			(layer "F.SilkS")
		)
		(fp_line
			(start 0.7874 0.4064)
			(end -0.7874 0.4064)
			(stroke
				(width 0.1524)
				(type default)
			)
			(layer "F.SilkS")
		)
		(fp_line
			(start -0.7874 0.4064)
			(end -0.7874 -0.4064)
			(stroke
				(width 0.1524)
				(type default)
			)
			(layer "F.SilkS")
		)
		(fp_line
			(start -0.12065 -0.305054)
			(end -0.12065 -0.2794)
			(stroke
				(width 0.1)
				(type default)
			)
			(layer "F.Fab")
		)
		(fp_line
			(start -0.67945 -0.305054)
			(end -0.12065 -0.305054)
			(stroke
				(width 0.1)
				(type default)
			)
			(layer "F.Fab")
		)
		(fp_line
			(start 0.67945 -0.3048)
			(end 0.67945 0.3048)
			(stroke
				(width 0.1)
				(type default)
			)
			(layer "F.Fab")
		)
		(fp_line
			(start 0.12065 -0.3048)
			(end 0.67945 -0.3048)
			(stroke
				(width 0.1)
				(type default)
			)
			(layer "F.Fab")
		)
		(fp_line
			(start 0.12065 -0.2794)
			(end 0.12065 -0.3048)
			(stroke
				(width 0.1)
				(type default)
			)
			(layer "F.Fab")
		)
		(fp_line
			(start -0.12065 -0.2794)
			(end 0.12065 -0.2794)
			(stroke
				(width 0.1)
				(type default)
			)
			(layer "F.Fab")
		)
		(fp_line
			(start 0.120396 0.2794)
			(end -0.12065 0.2794)
			(stroke
				(width 0.1)
				(type default)
			)
			(layer "F.Fab")
		)
		(fp_line
			(start -0.12065 0.2794)
			(end -0.12065 0.3048)
			(stroke
				(width 0.1)
				(type default)
			)
			(layer "F.Fab")
		)
		(fp_line
			(start 0.67945 0.3048)
			(end 0.120396 0.3048)
			(stroke
				(width 0.1)
				(type default)
			)
			(layer "F.Fab")
		)
		(fp_line
			(start 0.120396 0.3048)
			(end 0.120396 0.2794)
			(stroke
				(width 0.1)
				(type default)
			)
			(layer "F.Fab")
		)
		(fp_line
			(start -0.12065 0.3048)
			(end -0.67945 0.3048)
			(stroke
				(width 0.1)
				(type default)
			)
			(layer "F.Fab")
		)
		(fp_line
			(start -0.67945 0.3048)
			(end -0.67945 -0.305054)
			(stroke
				(width 0.1)
				(type default)
			)
			(layer "F.Fab")
		)
		(pad "1" smd circle
			(at -0.40005 0 90)
			(size 0 0)
			(layers "F.Cu" "F.Mask" "F.Paste")
			(net "SSD15_PWR_EN_R")
		)
		(pad "2" smd circle
			(at 0.40005 0 90)
			(size 0 0)
			(layers "F.Cu" "F.Mask" "F.Paste")
			(net "SSD15_PWR_EN")
		)
	)
	(footprint ""
		(layer "F.Cu")
		(at 210.439 -207.391 180)
		(property "Reference" "R1511"
			(at 0 0 180)
			(layer "F.SilkS")
			(hide yes)
			(effects
				(font
					(size 1.27 1.27)
				)
			)
		)
		(property "Value" ""
			(at 0 0 180)
			(layer "F.Fab")
			(effects
				(font
					(size 1.27 1.27)
				)
			)
		)
		(duplicate_pad_numbers_are_jumpers no)
		(fp_line
			(start 0.7874 0.4064)
			(end -0.7874 0.4064)
			(stroke
				(width 0.1524)
				(type default)
			)
			(layer "F.SilkS")
		)
		(fp_line
			(start 0.7874 -0.4064)
			(end 0.7874 0.4064)
			(stroke
				(width 0.1524)
				(type default)
			)
			(layer "F.SilkS")
		)
		(fp_line
			(start -0.7874 0.4064)
			(end -0.7874 -0.4064)
			(stroke
				(width 0.1524)
				(type default)
			)
			(layer "F.SilkS")
		)
		(fp_line
			(start -0.7874 -0.4064)
			(end 0.7874 -0.4064)
			(stroke
				(width 0.1524)
				(type default)
			)
			(layer "F.SilkS")
		)
		(fp_line
			(start 0.67945 0.3048)
			(end 0.120396 0.3048)
			(stroke
				(width 0.1)
				(type default)
			)
			(layer "F.Fab")
		)
		(fp_line
			(start 0.67945 -0.3048)
			(end 0.67945 0.3048)
			(stroke
				(width 0.1)
				(type default)
			)
			(layer "F.Fab")
		)
		(fp_line
			(start 0.12065 -0.2794)
			(end 0.12065 -0.3048)
			(stroke
				(width 0.1)
				(type default)
			)
			(layer "F.Fab")
		)
		(fp_line
			(start 0.12065 -0.3048)
			(end 0.67945 -0.3048)
			(stroke
				(width 0.1)
				(type default)
			)
			(layer "F.Fab")
		)
		(fp_line
			(start 0.120396 0.3048)
			(end 0.120396 0.2794)
			(stroke
				(width 0.1)
				(type default)
			)
			(layer "F.Fab")
		)
		(fp_line
			(start 0.120396 0.2794)
			(end -0.12065 0.2794)
			(stroke
				(width 0.1)
				(type default)
			)
			(layer "F.Fab")
		)
		(fp_line
			(start -0.12065 0.3048)
			(end -0.67945 0.3048)
			(stroke
				(width 0.1)
				(type default)
			)
			(layer "F.Fab")
		)
		(fp_line
			(start -0.12065 0.2794)
			(end -0.12065 0.3048)
			(stroke
				(width 0.1)
				(type default)
			)
			(layer "F.Fab")
		)
		(fp_line
			(start -0.12065 -0.2794)
			(end 0.12065 -0.2794)
			(stroke
				(width 0.1)
				(type default)
			)
			(layer "F.Fab")
		)
		(fp_line
			(start -0.12065 -0.305054)
			(end -0.12065 -0.2794)
			(stroke
				(width 0.1)
				(type default)
			)
			(layer "F.Fab")
		)
		(fp_line
			(start -0.67945 0.3048)
			(end -0.67945 -0.305054)
			(stroke
				(width 0.1)
				(type default)
			)
			(layer "F.Fab")
		)
		(fp_line
			(start -0.67945 -0.305054)
			(end -0.12065 -0.305054)
			(stroke
				(width 0.1)
				(type default)
			)
			(layer "F.Fab")
		)
		(pad "1" smd circle
			(at -0.40005 0 180)
			(size 0 0)
			(layers "F.Cu" "F.Mask" "F.Paste")
			(net "SMB_NIC4_R_SDA")
		)
		(pad "2" smd circle
			(at 0.40005 0 180)
			(size 0 0)
			(layers "F.Cu" "F.Mask" "F.Paste")
			(net "P1V2_AUX")
		)
	)
)
